(kicad_pcb
	(version 20260206)
	(generator "pcbnew")
	(generator_version "10.0")
	(general
		(thickness 1.6)
		(legacy_teardrops no)
	)
	(paper "A4")
	(title_block
		(title "01162023_DA0F0TEBIF0_F0T_Expander_BD_F_brd_V02_OCP.brd")
		(comment 1 "Grand Teton / footprints 1855-1860 of 9728")
	)
	(layers
		(0 "F.Cu" signal "TOP")
		(4 "In1.Cu" signal "GND")
		(6 "In2.Cu" signal "VCC")
		(8 "In3.Cu" signal "VCC1")
		(10 "In4.Cu" signal "GND1")
		(12 "In5.Cu" signal "IN1")
		(14 "In6.Cu" signal "GND2")
		(16 "In7.Cu" signal "IN2")
		(18 "In8.Cu" signal "GND3")
		(20 "In9.Cu" signal "IN3")
		(22 "In10.Cu" signal "GND4")
		(24 "In11.Cu" signal "IN4")
		(26 "In12.Cu" signal "GND5")
		(28 "In13.Cu" signal "IN5")
		(30 "In14.Cu" signal "GND6")
		(32 "In15.Cu" signal "IN6")
		(34 "In16.Cu" signal "GND7")
		(2 "B.Cu" signal "BOTTOM")
		(9 "F.Adhes" user "F.Adhesive")
		(11 "B.Adhes" user "B.Adhesive")
		(13 "F.Paste" user "Package Geometry/Pastemask Top")
		(15 "B.Paste" user "Package Geometry/Pastemask Bottom")
		(5 "F.SilkS" user "Ref Des/Silkscreen Top")
		(7 "B.SilkS" user "Ref Des/Silkscreen Bottom")
		(1 "F.Mask" user "Board Geometry/Soldermask Top")
		(3 "B.Mask" user "Board Geometry/Soldermask Bottom")
		(17 "Dwgs.User" user "User.Drawings")
		(19 "Cmts.User" user "User.Comments")
		(21 "Eco1.User" user "User.Eco1")
		(23 "Eco2.User" user "User.Eco2")
		(25 "Edge.Cuts" user "Board Geometry/Outline")
		(27 "Margin" user)
		(31 "F.CrtYd" user "Package Geometry/Place Bound Top")
		(29 "B.CrtYd" user "Package Geometry/Place Bound Bottom")
		(35 "F.Fab" user "Ref Des/Assembly Top")
		(33 "B.Fab" user "Ref Des/Assembly Bottom")
	)
	(footprint ""
		(layer "F.Cu")
		(at 121.13514 -92.605606)
		(property "Reference" "R1555"
			(at 0 0 0)
			(layer "F.SilkS")
			(hide yes)
			(effects
				(font
					(size 1.27 1.27)
				)
			)
		)
		(property "Value" ""
			(at 0 0 0)
			(layer "F.Fab")
			(effects
				(font
					(size 1.27 1.27)
				)
			)
		)
		(duplicate_pad_numbers_are_jumpers no)
		(fp_line
			(start -0.7874 -0.4064)
			(end 0.7874 -0.4064)
			(stroke
				(width 0.1524)
				(type default)
			)
			(layer "F.SilkS")
		)
		(fp_line
			(start -0.7874 0.4064)
			(end -0.7874 -0.4064)
			(stroke
				(width 0.1524)
				(type default)
			)
			(layer "F.SilkS")
		)
		(fp_line
			(start 0.7874 -0.4064)
			(end 0.7874 0.4064)
			(stroke
				(width 0.1524)
				(type default)
			)
			(layer "F.SilkS")
		)
		(fp_line
			(start 0.7874 0.4064)
			(end -0.7874 0.4064)
			(stroke
				(width 0.1524)
				(type default)
			)
			(layer "F.SilkS")
		)
		(fp_line
			(start -0.67945 -0.305054)
			(end -0.12065 -0.305054)
			(stroke
				(width 0.1)
				(type default)
			)
			(layer "F.Fab")
		)
		(fp_line
			(start -0.67945 0.3048)
			(end -0.67945 -0.305054)
			(stroke
				(width 0.1)
				(type default)
			)
			(layer "F.Fab")
		)
		(fp_line
			(start -0.12065 -0.305054)
			(end -0.12065 -0.2794)
			(stroke
				(width 0.1)
				(type default)
			)
			(layer "F.Fab")
		)
		(fp_line
			(start -0.12065 -0.2794)
			(end 0.12065 -0.2794)
			(stroke
				(width 0.1)
				(type default)
			)
			(layer "F.Fab")
		)
		(fp_line
			(start -0.12065 0.2794)
			(end -0.12065 0.3048)
			(stroke
				(width 0.1)
				(type default)
			)
			(layer "F.Fab")
		)
		(fp_line
			(start -0.12065 0.3048)
			(end -0.67945 0.3048)
			(stroke
				(width 0.1)
				(type default)
			)
			(layer "F.Fab")
		)
		(fp_line
			(start 0.120396 0.2794)
			(end -0.12065 0.2794)
			(stroke
				(width 0.1)
				(type default)
			)
			(layer "F.Fab")
		)
		(fp_line
			(start 0.120396 0.3048)
			(end 0.120396 0.2794)
			(stroke
				(width 0.1)
				(type default)
			)
			(layer "F.Fab")
		)
		(fp_line
			(start 0.12065 -0.3048)
			(end 0.67945 -0.3048)
			(stroke
				(width 0.1)
				(type default)
			)
			(layer "F.Fab")
		)
		(fp_line
			(start 0.12065 -0.2794)
			(end 0.12065 -0.3048)
			(stroke
				(width 0.1)
				(type default)
			)
			(layer "F.Fab")
		)
		(fp_line
			(start 0.67945 -0.3048)
			(end 0.67945 0.3048)
			(stroke
				(width 0.1)
				(type default)
			)
			(layer "F.Fab")
		)
		(fp_line
			(start 0.67945 0.3048)
			(end 0.120396 0.3048)
			(stroke
				(width 0.1)
				(type default)
			)
			(layer "F.Fab")
		)
		(pad "1" smd circle
			(at -0.40005 0)
			(size 0 0)
			(layers "F.Cu" "F.Mask" "F.Paste")
			(net "P3V3_AUX")
		)
		(pad "2" smd circle
			(at 0.40005 0)
			(size 0 0)
			(layers "F.Cu" "F.Mask" "F.Paste")
			(net "SMB_BIC_I2C9_MUX0_SSD2_R_SDA")
		)
	)
	(footprint ""
		(layer "F.Cu")
		(at 7.849362 -251.312426 -90)
		(property "Reference" "C4226"
			(at 0 0 270)
			(layer "F.SilkS")
			(hide yes)
			(effects
				(font
					(size 1.27 1.27)
				)
			)
		)
		(property "Value" ""
			(at 0 0 270)
			(layer "F.Fab")
			(effects
				(font
					(size 1.27 1.27)
				)
			)
		)
		(duplicate_pad_numbers_are_jumpers no)
		(fp_line
			(start -1.2954 0.5842)
			(end -1.2954 -0.5842)
			(stroke
				(width 0.1524)
				(type default)
			)
			(layer "F.SilkS")
		)
		(fp_line
			(start 1.2954 0.5842)
			(end -1.2954 0.5842)
			(stroke
				(width 0.1524)
				(type default)
			)
			(layer "F.SilkS")
		)
		(fp_line
			(start -1.2954 -0.5842)
			(end 1.2954 -0.5842)
			(stroke
				(width 0.1524)
				(type default)
			)
			(layer "F.SilkS")
		)
		(fp_line
			(start 1.2954 -0.5842)
			(end 1.2954 0.5842)
			(stroke
				(width 0.1524)
				(type default)
			)
			(layer "F.SilkS")
		)
		(fp_line
			(start -0.8636 0.4572)
			(end -0.8636 0.4064)
			(stroke
				(width 0.1)
				(type default)
			)
			(layer "F.Fab")
		)
		(fp_line
			(start 0.8636 0.4572)
			(end -0.8636 0.4572)
			(stroke
				(width 0.1)
				(type default)
			)
			(layer "F.Fab")
		)
		(fp_line
			(start -1.1938 0.4064)
			(end -1.1938 -0.4064)
			(stroke
				(width 0.1)
				(type default)
			)
			(layer "F.Fab")
		)
		(fp_line
			(start -0.8636 0.4064)
			(end -1.1938 0.4064)
			(stroke
				(width 0.1)
				(type default)
			)
			(layer "F.Fab")
		)
		(fp_line
			(start 0.8636 0.4064)
			(end 0.8636 0.4572)
			(stroke
				(width 0.1)
				(type default)
			)
			(layer "F.Fab")
		)
		(fp_line
			(start 1.1938 0.4064)
			(end 0.8636 0.4064)
			(stroke
				(width 0.1)
				(type default)
			)
			(layer "F.Fab")
		)
		(fp_line
			(start -1.1938 -0.4064)
			(end -0.8636 -0.4064)
			(stroke
				(width 0.1)
				(type default)
			)
			(layer "F.Fab")
		)
		(fp_line
			(start -0.8636 -0.4064)
			(end -0.8636 -0.4572)
			(stroke
				(width 0.1)
				(type default)
			)
			(layer "F.Fab")
		)
		(fp_line
			(start 0.8636 -0.4064)
			(end 1.1938 -0.4064)
			(stroke
				(width 0.1)
				(type default)
			)
			(layer "F.Fab")
		)
		(fp_line
			(start 1.1938 -0.4064)
			(end 1.1938 0.4064)
			(stroke
				(width 0.1)
				(type default)
			)
			(layer "F.Fab")
		)
		(fp_line
			(start -0.8636 -0.4572)
			(end 0.8636 -0.4572)
			(stroke
				(width 0.1)
				(type default)
			)
			(layer "F.Fab")
		)
		(fp_line
			(start 0.8636 -0.4572)
			(end 0.8636 -0.4064)
			(stroke
				(width 0.1)
				(type default)
			)
			(layer "F.Fab")
		)
		(pad "1" smd rect
			(at -0.7366 0 180)
			(size 0.7112 0.8128)
			(layers "F.Cu" "F.Mask" "F.Paste")
			(net "P1V25_SERDES_VDDPLL_PEX0_C0")
		)
		(pad "2" smd rect
			(at 0.7366 0 180)
			(size 0.7112 0.8128)
			(layers "F.Cu" "F.Mask" "F.Paste")
			(net "GND")
		)
	)
	(footprint ""
		(layer "F.Cu")
		(at 420.746428 -58.323734)
		(property "Reference" "PC439"
			(at 0 0 0)
			(layer "F.SilkS")
			(hide yes)
			(effects
				(font
					(size 1.27 1.27)
				)
			)
		)
		(property "Value" ""
			(at 0 0 0)
			(layer "F.Fab")
			(effects
				(font
					(size 1.27 1.27)
				)
			)
		)
		(duplicate_pad_numbers_are_jumpers no)
		(fp_line
			(start -1.524 -0.762)
			(end 1.524 -0.762)
			(stroke
				(width 0.1524)
				(type default)
			)
			(layer "F.SilkS")
		)
		(fp_line
			(start -1.524 0.762)
			(end -1.524 -0.762)
			(stroke
				(width 0.1524)
				(type default)
			)
			(layer "F.SilkS")
		)
		(fp_line
			(start 1.524 -0.762)
			(end 1.524 0.762)
			(stroke
				(width 0.1524)
				(type default)
			)
			(layer "F.SilkS")
		)
		(fp_line
			(start 1.524 0.762)
			(end -1.524 0.762)
			(stroke
				(width 0.1524)
				(type default)
			)
			(layer "F.SilkS")
		)
		(fp_line
			(start -1.1049 -0.724916)
			(end -1.1049 0.724916)
			(stroke
				(width 0.1)
				(type default)
			)
			(layer "F.Fab")
		)
		(fp_line
			(start -1.1049 0.724916)
			(end 1.1049 0.724916)
			(stroke
				(width 0.1)
				(type default)
			)
			(layer "F.Fab")
		)
		(fp_line
			(start 1.1049 -0.724916)
			(end -1.1049 -0.724916)
			(stroke
				(width 0.1)
				(type default)
			)
			(layer "F.Fab")
		)
		(fp_line
			(start 1.1049 0.724916)
			(end 1.1049 -0.724916)
			(stroke
				(width 0.1)
				(type default)
			)
			(layer "F.Fab")
		)
		(pad "1" smd rect
			(at -0.889 0 180)
			(size 1.016 1.27)
			(layers "F.Cu" "F.Mask" "F.Paste")
			(net "GND")
		)
		(pad "2" smd rect
			(at 0.889 0 180)
			(size 1.016 1.27)
			(layers "F.Cu" "F.Mask" "F.Paste")
			(net "P12V_AUX")
		)
	)
	(footprint ""
		(layer "F.Cu")
		(at 145.988278 -260.84911 -90)
		(property "Reference" "C3193"
			(at 0 0 270)
			(layer "F.SilkS")
			(hide yes)
			(effects
				(font
					(size 1.27 1.27)
				)
			)
		)
		(property "Value" ""
			(at 0 0 270)
			(layer "F.Fab")
			(effects
				(font
					(size 1.27 1.27)
				)
			)
		)
		(duplicate_pad_numbers_are_jumpers no)
		(fp_line
			(start -1.2954 0.5842)
			(end -1.2954 -0.5842)
			(stroke
				(width 0.1524)
				(type default)
			)
			(layer "F.SilkS")
		)
		(fp_line
			(start 1.2954 0.5842)
			(end -1.2954 0.5842)
			(stroke
				(width 0.1524)
				(type default)
			)
			(layer "F.SilkS")
		)
		(fp_line
			(start -1.2954 -0.5842)
			(end 1.2954 -0.5842)
			(stroke
				(width 0.1524)
				(type default)
			)
			(layer "F.SilkS")
		)
		(fp_line
			(start 1.2954 -0.5842)
			(end 1.2954 0.5842)
			(stroke
				(width 0.1524)
				(type default)
			)
			(layer "F.SilkS")
		)
		(fp_line
			(start -0.8636 0.4572)
			(end -0.8636 0.4064)
			(stroke
				(width 0.1)
				(type default)
			)
			(layer "F.Fab")
		)
		(fp_line
			(start 0.8636 0.4572)
			(end -0.8636 0.4572)
			(stroke
				(width 0.1)
				(type default)
			)
			(layer "F.Fab")
		)
		(fp_line
			(start -1.1938 0.4064)
			(end -1.1938 -0.4064)
			(stroke
				(width 0.1)
				(type default)
			)
			(layer "F.Fab")
		)
		(fp_line
			(start -0.8636 0.4064)
			(end -1.1938 0.4064)
			(stroke
				(width 0.1)
				(type default)
			)
			(layer "F.Fab")
		)
		(fp_line
			(start 0.8636 0.4064)
			(end 0.8636 0.4572)
			(stroke
				(width 0.1)
				(type default)
			)
			(layer "F.Fab")
		)
		(fp_line
			(start 1.1938 0.4064)
			(end 0.8636 0.4064)
			(stroke
				(width 0.1)
				(type default)
			)
			(layer "F.Fab")
		)
		(fp_line
			(start -1.1938 -0.4064)
			(end -0.8636 -0.4064)
			(stroke
				(width 0.1)
				(type default)
			)
			(layer "F.Fab")
		)
		(fp_line
			(start -0.8636 -0.4064)
			(end -0.8636 -0.4572)
			(stroke
				(width 0.1)
				(type default)
			)
			(layer "F.Fab")
		)
		(fp_line
			(start 0.8636 -0.4064)
			(end 1.1938 -0.4064)
			(stroke
				(width 0.1)
				(type default)
			)
			(layer "F.Fab")
		)
		(fp_line
			(start 1.1938 -0.4064)
			(end 1.1938 0.4064)
			(stroke
				(width 0.1)
				(type default)
			)
			(layer "F.Fab")
		)
		(fp_line
			(start -0.8636 -0.4572)
			(end 0.8636 -0.4572)
			(stroke
				(width 0.1)
				(type default)
			)
			(layer "F.Fab")
		)
		(fp_line
			(start 0.8636 -0.4572)
			(end 0.8636 -0.4064)
			(stroke
				(width 0.1)
				(type default)
			)
			(layer "F.Fab")
		)
		(pad "1" smd rect
			(at -0.7366 0 180)
			(size 0.7112 0.8128)
			(layers "F.Cu" "F.Mask" "F.Paste")
			(net "P1V8_PLL0_PEX1")
		)
		(pad "2" smd rect
			(at 0.7366 0 180)
			(size 0.7112 0.8128)
			(layers "F.Cu" "F.Mask" "F.Paste")
			(net "GND")
		)
	)
	(footprint ""
		(layer "F.Cu")
		(at 327.533 -215.265 180)
		(property "Reference" "R4157"
			(at 0 0 180)
			(layer "F.SilkS")
			(hide yes)
			(effects
				(font
					(size 1.27 1.27)
				)
			)
		)
		(property "Value" ""
			(at 0 0 180)
			(layer "F.Fab")
			(effects
				(font
					(size 1.27 1.27)
				)
			)
		)
		(duplicate_pad_numbers_are_jumpers no)
		(fp_line
			(start 0.7874 0.4064)
			(end -0.7874 0.4064)
			(stroke
				(width 0.1524)
				(type default)
			)
			(layer "F.SilkS")
		)
		(fp_line
			(start 0.7874 -0.4064)
			(end 0.7874 0.4064)
			(stroke
				(width 0.1524)
				(type default)
			)
			(layer "F.SilkS")
		)
		(fp_line
			(start -0.7874 0.4064)
			(end -0.7874 -0.4064)
			(stroke
				(width 0.1524)
				(type default)
			)
			(layer "F.SilkS")
		)
		(fp_line
			(start -0.7874 -0.4064)
			(end 0.7874 -0.4064)
			(stroke
				(width 0.1524)
				(type default)
			)
			(layer "F.SilkS")
		)
		(fp_line
			(start 0.67945 0.3048)
			(end 0.120396 0.3048)
			(stroke
				(width 0.1)
				(type default)
			)
			(layer "F.Fab")
		)
		(fp_line
			(start 0.67945 -0.3048)
			(end 0.67945 0.3048)
			(stroke
				(width 0.1)
				(type default)
			)
			(layer "F.Fab")
		)
		(fp_line
			(start 0.12065 -0.2794)
			(end 0.12065 -0.3048)
			(stroke
				(width 0.1)
				(type default)
			)
			(layer "F.Fab")
		)
		(fp_line
			(start 0.12065 -0.3048)
			(end 0.67945 -0.3048)
			(stroke
				(width 0.1)
				(type default)
			)
			(layer "F.Fab")
		)
		(fp_line
			(start 0.120396 0.3048)
			(end 0.120396 0.2794)
			(stroke
				(width 0.1)
				(type default)
			)
			(layer "F.Fab")
		)
		(fp_line
			(start 0.120396 0.2794)
			(end -0.12065 0.2794)
			(stroke
				(width 0.1)
				(type default)
			)
			(layer "F.Fab")
		)
		(fp_line
			(start -0.12065 0.3048)
			(end -0.67945 0.3048)
			(stroke
				(width 0.1)
				(type default)
			)
			(layer "F.Fab")
		)
		(fp_line
			(start -0.12065 0.2794)
			(end -0.12065 0.3048)
			(stroke
				(width 0.1)
				(type default)
			)
			(layer "F.Fab")
		)
		(fp_line
			(start -0.12065 -0.2794)
			(end 0.12065 -0.2794)
			(stroke
				(width 0.1)
				(type default)
			)
			(layer "F.Fab")
		)
		(fp_line
			(start -0.12065 -0.305054)
			(end -0.12065 -0.2794)
			(stroke
				(width 0.1)
				(type default)
			)
			(layer "F.Fab")
		)
		(fp_line
			(start -0.67945 0.3048)
			(end -0.67945 -0.305054)
			(stroke
				(width 0.1)
				(type default)
			)
			(layer "F.Fab")
		)
		(fp_line
			(start -0.67945 -0.305054)
			(end -0.12065 -0.305054)
			(stroke
				(width 0.1)
				(type default)
			)
			(layer "F.Fab")
		)
		(pad "1" smd circle
			(at -0.40005 0 180)
			(size 0 0)
			(layers "F.Cu" "F.Mask" "F.Paste")
			(net "PRSNT_SSD10_FPGA_N")
		)
		(pad "2" smd circle
			(at 0.40005 0 180)
			(size 0 0)
			(layers "F.Cu" "F.Mask" "F.Paste")
			(net "PRSNT_SSD10_FPGA_R_N")
		)
	)
	(footprint ""
		(layer "F.Cu")
		(at 150.331932 -388.21741 90)
		(property "Reference" "C4097"
			(at 0 0 90)
			(layer "F.SilkS")
			(hide yes)
			(effects
				(font
					(size 1.27 1.27)
				)
			)
		)
		(property "Value" ""
			(at 0 0 90)
			(layer "F.Fab")
			(effects
				(font
					(size 1.27 1.27)
				)
			)
		)
		(duplicate_pad_numbers_are_jumpers no)
		(fp_line
			(start 0.7874 -0.4064)
			(end 0.7874 0.4064)
			(stroke
				(width 0.1524)
				(type default)
			)
			(layer "F.SilkS")
		)
		(fp_line
			(start -0.7874 -0.4064)
			(end 0.7874 -0.4064)
			(stroke
				(width 0.1524)
				(type default)
			)
			(layer "F.SilkS")
		)
		(fp_line
			(start 0.7874 0.4064)
			(end -0.7874 0.4064)
			(stroke
				(width 0.1524)
				(type default)
			)
			(layer "F.SilkS")
		)
		(fp_line
			(start -0.7874 0.4064)
			(end -0.7874 -0.4064)
			(stroke
				(width 0.1524)
				(type default)
			)
			(layer "F.SilkS")
		)
		(fp_line
			(start -0.12065 -0.305054)
			(end -0.12065 -0.2794)
			(stroke
				(width 0.1)
				(type default)
			)
			(layer "F.Fab")
		)
		(fp_line
			(start -0.67945 -0.305054)
			(end -0.12065 -0.305054)
			(stroke
				(width 0.1)
				(type default)
			)
			(layer "F.Fab")
		)
		(fp_line
			(start 0.67945 -0.3048)
			(end 0.67945 0.3048)
			(stroke
				(width 0.1)
				(type default)
			)
			(layer "F.Fab")
		)
		(fp_line
			(start 0.12065 -0.3048)
			(end 0.67945 -0.3048)
			(stroke
				(width 0.1)
				(type default)
			)
			(layer "F.Fab")
		)
		(fp_line
			(start 0.12065 -0.2794)
			(end 0.12065 -0.3048)
			(stroke
				(width 0.1)
				(type default)
			)
			(layer "F.Fab")
		)
		(fp_line
			(start -0.12065 -0.2794)
			(end 0.12065 -0.2794)
			(stroke
				(width 0.1)
				(type default)
			)
			(layer "F.Fab")
		)
		(fp_line
			(start 0.120396 0.2794)
			(end -0.12065 0.2794)
			(stroke
				(width 0.1)
				(type default)
			)
			(layer "F.Fab")
		)
		(fp_line
			(start -0.12065 0.2794)
			(end -0.12065 0.3048)
			(stroke
				(width 0.1)
				(type default)
			)
			(layer "F.Fab")
		)
		(fp_line
			(start 0.67945 0.3048)
			(end 0.120396 0.3048)
			(stroke
				(width 0.1)
				(type default)
			)
			(layer "F.Fab")
		)
		(fp_line
			(start 0.120396 0.3048)
			(end 0.120396 0.2794)
			(stroke
				(width 0.1)
				(type default)
			)
			(layer "F.Fab")
		)
		(fp_line
			(start -0.12065 0.3048)
			(end -0.67945 0.3048)
			(stroke
				(width 0.1)
				(type default)
			)
			(layer "F.Fab")
		)
		(fp_line
			(start -0.67945 0.3048)
			(end -0.67945 -0.305054)
			(stroke
				(width 0.1)
				(type default)
			)
			(layer "F.Fab")
		)
		(pad "1" smd circle
			(at -0.40005 0 90)
			(size 0 0)
			(layers "F.Cu" "F.Mask" "F.Paste")
			(net "GND")
		)
		(pad "2" smd circle
			(at 0.40005 0 90)
			(size 0 0)
			(layers "F.Cu" "F.Mask" "F.Paste")
			(net "PRSNT_GPU_HMC_N")
		)
	)
)
